(kicad_pcb
	(version 20260206)
	(generator "pcbnew")
	(generator_version "10.0")
	(general
		(thickness 1.5755)
		(legacy_teardrops no)
	)
	(paper "A4")
	(title_block
		(title "gnss-rcb-f9t — GPS_MODULE_ZED-F9T.PcbDoc")
		(comment 1 "Time Appliance Project (Time Card) / footprints 40-44 of 44")
	)
	(layers
		(0 "F.Cu" signal "Top Layer")
		(4 "In1.Cu" signal "Int1 (GND)")
		(6 "In2.Cu" signal "Int2 (GND)")
		(2 "B.Cu" signal "Bottom Layer")
		(9 "F.Adhes" user "F.Adhesive")
		(11 "B.Adhes" user "B.Adhesive")
		(13 "F.Paste" user "Top Paste")
		(15 "B.Paste" user "Bottom Paste")
		(5 "F.SilkS" user "Top Overlay")
		(7 "B.SilkS" user "Bottom Overlay")
		(1 "F.Mask" user "Top Solder")
		(3 "B.Mask" user "Bottom Solder")
		(17 "Dwgs.User" user "User.Drawings")
		(19 "Cmts.User" user "User.Comments")
		(21 "Eco1.User" user "User.Eco1")
		(23 "Eco2.User" user "User.Eco2")
		(25 "Edge.Cuts" user)
		(27 "Margin" user)
		(31 "F.CrtYd" user "Top Courtyard")
		(29 "B.CrtYd" user "Bottom Courtyard")
		(35 "F.Fab" user "Top Component Outline")
		(33 "B.Fab" user "Bottom Component Outline")
	)
	(footprint "Vault:DCK0005A_N"
		(layer "F.Cu")
		(at 130.4091 104.4931 90)
		(property "Reference" "U4"
			(at 2.30853 -0.104 0)
			(unlocked yes)
			(layer "F.SilkS")
			(effects
				(font
					(size 0.8 0.8)
					(thickness 0.15)
				)
			)
		)
		(property "Value" "LPV511MGX/NOPB"
			(at -2.962402 8.848615 0)
			(unlocked yes)
			(layer "F.SilkS")
			(hide yes)
			(effects
				(font
					(size 1.524 1.524)
					(thickness 0.254)
				)
			)
		)
		(sheetname "Antenna_Supervisor")
		(sheetfile "Antenna_Supervisor.kicad_sch")
		(duplicate_pad_numbers_are_jumpers no)
		(fp_line
			(start 0.3 -1.1)
			(end 0.3 1.1)
			(stroke
				(width 0.2)
				(type solid)
			)
			(layer "F.SilkS")
		)
		(fp_line
			(start -0.3 -1.1)
			(end 0.3 -1.1)
			(stroke
				(width 0.2)
				(type solid)
			)
			(layer "F.SilkS")
		)
		(fp_line
			(start -0.3 -1.1)
			(end -0.3 1.1)
			(stroke
				(width 0.2)
				(type solid)
			)
			(layer "F.SilkS")
		)
		(fp_line
			(start -0.3 1.1)
			(end 0.3 1.1)
			(stroke
				(width 0.2)
				(type solid)
			)
			(layer "F.SilkS")
		)
		(fp_circle
			(center -1.125 -1.4)
			(end -1 -1.4)
			(stroke
				(width 0.25)
				(type solid)
			)
			(fill no)
			(layer "F.SilkS")
		)
		(fp_line
			(start 1.8 -1.35)
			(end 1.8 1.35)
			(stroke
				(width 0.05)
				(type solid)
			)
			(layer "F.CrtYd")
		)
		(fp_line
			(start -1.8 -1.35)
			(end 1.8 -1.35)
			(stroke
				(width 0.05)
				(type solid)
			)
			(layer "F.CrtYd")
		)
		(fp_line
			(start -1.8 -1.35)
			(end -1.8 1.35)
			(stroke
				(width 0.05)
				(type solid)
			)
			(layer "F.CrtYd")
		)
		(fp_line
			(start 0 -0.5)
			(end 0 0.5)
			(stroke
				(width 0.1)
				(type solid)
			)
			(layer "F.CrtYd")
		)
		(fp_line
			(start -0.5 0)
			(end 0.5 0)
			(stroke
				(width 0.1)
				(type solid)
			)
			(layer "F.CrtYd")
		)
		(fp_line
			(start -1.8 1.35)
			(end 1.8 1.35)
			(stroke
				(width 0.05)
				(type solid)
			)
			(layer "F.CrtYd")
		)
		(pad "1" smd roundrect
			(at -1.125 -0.65 180)
			(size 0.4 0.85)
			(layers "F.Cu" "F.Mask" "F.Paste")
			(roundrect_rratio 0.125)
			(net "NetU3_1")
		)
		(pad "2" smd roundrect
			(at -1.125 0 180)
			(size 0.4 0.85)
			(layers "F.Cu" "F.Mask" "F.Paste")
			(roundrect_rratio 0.125)
			(net "GND")
		)
		(pad "3" smd roundrect
			(at -1.125 0.65 180)
			(size 0.4 0.85)
			(layers "F.Cu" "F.Mask" "F.Paste")
			(roundrect_rratio 0.125)
			(net "NetR10_1")
		)
		(pad "4" smd roundrect
			(at 1.125 0.65 180)
			(size 0.4 0.85)
			(layers "F.Cu" "F.Mask" "F.Paste")
			(roundrect_rratio 0.125)
			(net "NetC10_1")
		)
		(pad "5" smd roundrect
			(at 1.125 -0.65 180)
			(size 0.4 0.85)
			(layers "F.Cu" "F.Mask" "F.Paste")
			(roundrect_rratio 0.125)
			(net "VCC")
		)
	)
	(footprint "Vault:RESC1608X055N"
		(layer "F.Cu")
		(at 127.9961 108.4301 90)
		(property "Reference" "R12"
			(at -2.26347 -0.231005 0)
			(unlocked yes)
			(layer "F.SilkS")
			(effects
				(font
					(size 0.8 0.8)
					(thickness 0.15)
				)
			)
		)
		(property "Value" "Vishay_RCP0603W25R0GEB"
			(at -2.378202 15.323605 0)
			(unlocked yes)
			(layer "F.SilkS")
			(hide yes)
			(effects
				(font
					(size 1.524 1.524)
					(thickness 0.254)
				)
			)
		)
		(sheetname "Antenna_Supervisor")
		(sheetfile "Antenna_Supervisor.kicad_sch")
		(duplicate_pad_numbers_are_jumpers no)
		(fp_line
			(start 1.5 -0.75)
			(end 1.5 0.75)
			(stroke
				(width 0.1)
				(type solid)
			)
			(layer "F.CrtYd")
		)
		(fp_line
			(start -1.5 -0.75)
			(end 1.5 -0.75)
			(stroke
				(width 0.1)
				(type solid)
			)
			(layer "F.CrtYd")
		)
		(fp_line
			(start -1.5 -0.75)
			(end -1.5 0.75)
			(stroke
				(width 0.1)
				(type solid)
			)
			(layer "F.CrtYd")
		)
		(fp_line
			(start -1.5 0.75)
			(end 1.5 0.75)
			(stroke
				(width 0.1)
				(type solid)
			)
			(layer "F.CrtYd")
		)
		(fp_line
			(start 0.80017 -0.40012)
			(end 0.80017 0.39984)
			(stroke
				(width 0.05)
				(type solid)
			)
			(layer "F.Fab")
		)
		(fp_line
			(start -0.79991 -0.40012)
			(end 0.80017 -0.40012)
			(stroke
				(width 0.05)
				(type solid)
			)
			(layer "F.Fab")
		)
		(fp_line
			(start -0.79991 -0.40012)
			(end -0.79991 0.39984)
			(stroke
				(width 0.05)
				(type solid)
			)
			(layer "F.Fab")
		)
		(fp_line
			(start -0.79991 0.39984)
			(end 0.80017 0.39984)
			(stroke
				(width 0.05)
				(type solid)
			)
			(layer "F.Fab")
		)
		(fp_text_box "${REFERENCE}"
			(start -1.09004 -0.20727)
			(end 1.09004 0.20726)
			(margins 0 0 0 0)
			(layer "F.Fab")
			(effects
				(font
					(face "Arial")
					(size 0.315 0.315)
					(thickness 0.254)
				)
				(justify top)
			)
			(border no)
			(stroke
				(width 0.1)
				(type default)
			)
			(knockout no)
		)
		(pad "1" smd rect
			(at -0.8 0 90)
			(size 0.9 1)
			(layers "F.Cu" "F.Mask" "F.Paste")
			(net "NetQ1_3")
			(solder_mask_margin 0.05)
			(solder_paste_margin 0)
		)
		(pad "2" smd rect
			(at 0.8 0 90)
			(size 0.9 1)
			(layers "F.Cu" "F.Mask" "F.Paste")
			(net "NetC10_1")
			(solder_mask_margin 0.05)
			(solder_paste_margin 0)
		)
	)
	(footprint "Vault:SOT23_3pins_300x140x112"
		(layer "F.Cu")
		(at 130.0281 113.1291)
		(property "Reference" "Q1"
			(at -2.7202 1.32367 0)
			(unlocked yes)
			(layer "F.SilkS")
			(effects
				(font
					(size 0.8 0.8)
					(thickness 0.15)
				)
			)
		)
		(property "Value" "onsemi_NTR2101PT1G"
			(at 11.61631 3.673602 0)
			(unlocked yes)
			(layer "F.SilkS")
			(hide yes)
			(effects
				(font
					(size 1.524 1.524)
					(thickness 0.254)
				)
			)
		)
		(sheetname "Antenna_Supervisor")
		(sheetfile "Antenna_Supervisor.kicad_sch")
		(duplicate_pad_numbers_are_jumpers no)
		(fp_line
			(start -1.7 -0.9)
			(end -0.7 -0.9)
			(stroke
				(width 0.1)
				(type solid)
			)
			(layer "F.SilkS")
		)
		(fp_line
			(start -1.7 0.7)
			(end -1.7 -0.9)
			(stroke
				(width 0.1)
				(type solid)
			)
			(layer "F.SilkS")
		)
		(fp_line
			(start -0.3 0.9)
			(end 0.3 0.9)
			(stroke
				(width 0.1)
				(type solid)
			)
			(layer "F.SilkS")
		)
		(fp_line
			(start 0.7 -0.9)
			(end 1.7 -0.9)
			(stroke
				(width 0.1)
				(type solid)
			)
			(layer "F.SilkS")
		)
		(fp_line
			(start 1.7 0.7)
			(end 1.7 -0.9)
			(stroke
				(width 0.1)
				(type solid)
			)
			(layer "F.SilkS")
		)
		(fp_circle
			(center -1 1.9)
			(end -1 1.8)
			(stroke
				(width 0.2)
				(type solid)
			)
			(fill no)
			(layer "F.SilkS")
		)
		(fp_line
			(start -1.8 -1.8)
			(end 1.8 -1.8)
			(stroke
				(width 0.1)
				(type solid)
			)
			(layer "F.CrtYd")
		)
		(fp_line
			(start -1.8 1.8)
			(end -1.8 -1.8)
			(stroke
				(width 0.1)
				(type solid)
			)
			(layer "F.CrtYd")
		)
		(fp_line
			(start -1.8 1.8)
			(end 1.8 1.8)
			(stroke
				(width 0.1)
				(type solid)
			)
			(layer "F.CrtYd")
		)
		(fp_line
			(start 1.8 1.8)
			(end 1.8 -1.8)
			(stroke
				(width 0.1)
				(type solid)
			)
			(layer "F.CrtYd")
		)
		(fp_line
			(start -1.5 -0.7)
			(end 1.5 -0.7)
			(stroke
				(width 0.1)
				(type solid)
			)
			(layer "F.Fab")
		)
		(fp_line
			(start -1.5 0.7)
			(end -1.5 -0.7)
			(stroke
				(width 0.1)
				(type solid)
			)
			(layer "F.Fab")
		)
		(fp_line
			(start -1.5 0.7)
			(end 1.5 0.7)
			(stroke
				(width 0.1)
				(type solid)
			)
			(layer "F.Fab")
		)
		(fp_line
			(start -1.205 1.2)
			(end -1.205 0.705)
			(stroke
				(width 0.1)
				(type solid)
			)
			(layer "F.Fab")
		)
		(fp_line
			(start -1.205 1.2)
			(end -0.695 1.2)
			(stroke
				(width 0.1)
				(type solid)
			)
			(layer "F.Fab")
		)
		(fp_line
			(start -0.695 1.2)
			(end -0.695 0.705)
			(stroke
				(width 0.1)
				(type solid)
			)
			(layer "F.Fab")
		)
		(fp_line
			(start -0.255 -1.2)
			(end -0.255 -0.705)
			(stroke
				(width 0.1)
				(type solid)
			)
			(layer "F.Fab")
		)
		(fp_line
			(start -0.255 -1.2)
			(end 0.255 -1.2)
			(stroke
				(width 0.1)
				(type solid)
			)
			(layer "F.Fab")
		)
		(fp_line
			(start 0.255 -0.705)
			(end 0.255 -1.2)
			(stroke
				(width 0.1)
				(type solid)
			)
			(layer "F.Fab")
		)
		(fp_line
			(start 0.695 1.2)
			(end 0.695 0.705)
			(stroke
				(width 0.1)
				(type solid)
			)
			(layer "F.Fab")
		)
		(fp_line
			(start 0.695 1.2)
			(end 1.205 1.2)
			(stroke
				(width 0.1)
				(type solid)
			)
			(layer "F.Fab")
		)
		(fp_line
			(start 1.205 1.2)
			(end 1.205 0.705)
			(stroke
				(width 0.1)
				(type solid)
			)
			(layer "F.Fab")
		)
		(fp_line
			(start 1.5 0.7)
			(end 1.5 -0.7)
			(stroke
				(width 0.1)
				(type solid)
			)
			(layer "F.Fab")
		)
		(fp_text_box "${REFERENCE}"
			(start -1.09004 -0.20727)
			(end 1.09004 0.20726)
			(margins 0 0 0 0)
			(layer "F.Fab")
			(effects
				(font
					(face "Arial")
					(size 0.315 0.315)
					(thickness 0.254)
				)
				(justify top)
			)
			(border no)
			(stroke
				(width 0.1)
				(type default)
			)
			(knockout no)
		)
		(pad "1" smd rect
			(at -0.95 1)
			(size 0.8 0.9)
			(layers "F.Cu" "F.Mask" "F.Paste")
			(net "NetQ1_1")
			(solder_mask_margin 0.05)
			(solder_paste_margin 0)
		)
		(pad "2" smd rect
			(at 0.95 1)
			(size 0.8 0.9)
			(layers "F.Cu" "F.Mask" "F.Paste")
			(net "VCC_ANT")
			(solder_mask_margin 0.05)
			(solder_paste_margin 0)
		)
		(pad "3" smd rect
			(at 0 -1)
			(size 0.8 0.9)
			(layers "F.Cu" "F.Mask" "F.Paste")
			(net "NetQ1_3")
			(solder_mask_margin 0.05)
			(solder_paste_margin 0)
		)
	)
	(footprint "Vault:CAPC1005X055N"
		(layer "F.Cu")
		(at 156.4441 105.6361)
		(property "Reference" "C3"
			(at 2.055 0.15527 0)
			(unlocked yes)
			(layer "F.SilkS")
			(effects
				(font
					(size 0.8 0.8)
					(thickness 0.15)
				)
			)
		)
		(property "Value" "Murata_GRM155R61E105KA12D"
			(at 17.659825 2.124202 0)
			(unlocked yes)
			(layer "F.SilkS")
			(hide yes)
			(effects
				(font
					(size 1.524 1.524)
					(thickness 0.254)
				)
			)
		)
		(sheetname "ZED-F9T")
		(sheetfile "ZED-F9T.kicad_sch")
		(duplicate_pad_numbers_are_jumpers no)
		(fp_line
			(start -0.95 -0.5)
			(end 0.95 -0.5)
			(stroke
				(width 0.1)
				(type solid)
			)
			(layer "F.CrtYd")
		)
		(fp_line
			(start -0.95 0.5)
			(end -0.95 -0.5)
			(stroke
				(width 0.1)
				(type solid)
			)
			(layer "F.CrtYd")
		)
		(fp_line
			(start -0.95 0.5)
			(end 0.95 0.5)
			(stroke
				(width 0.1)
				(type solid)
			)
			(layer "F.CrtYd")
		)
		(fp_line
			(start 0.95 0.5)
			(end 0.95 -0.5)
			(stroke
				(width 0.1)
				(type solid)
			)
			(layer "F.CrtYd")
		)
		(fp_line
			(start -0.5 -0.25)
			(end 0.5 -0.25)
			(stroke
				(width 0.05)
				(type solid)
			)
			(layer "F.Fab")
		)
		(fp_line
			(start -0.5 0.25)
			(end -0.5 -0.25)
			(stroke
				(width 0.05)
				(type solid)
			)
			(layer "F.Fab")
		)
		(fp_line
			(start -0.5 0.25)
			(end 0.5 0.25)
			(stroke
				(width 0.05)
				(type solid)
			)
			(layer "F.Fab")
		)
		(fp_line
			(start 0.5 0.25)
			(end 0.5 -0.25)
			(stroke
				(width 0.05)
				(type solid)
			)
			(layer "F.Fab")
		)
		(fp_text_box "${REFERENCE}"
			(start -1.09004 -0.20727)
			(end 1.09004 0.20726)
			(margins 0 0 0 0)
			(layer "F.Fab")
			(effects
				(font
					(face "Arial")
					(size 0.315 0.315)
					(thickness 0.254)
				)
				(justify top)
			)
			(border no)
			(stroke
				(width 0.1)
				(type default)
			)
			(knockout no)
		)
		(pad "1" smd rect
			(at -0.46 0)
			(size 0.6 0.62)
			(layers "F.Cu" "F.Mask" "F.Paste")
			(net "VCC")
			(solder_mask_margin 0.05)
			(solder_paste_margin 0)
		)
		(pad "2" smd rect
			(at 0.46 0)
			(size 0.6 0.62)
			(layers "F.Cu" "F.Mask" "F.Paste")
			(net "GND")
			(solder_mask_margin 0.05)
			(solder_paste_margin 0)
		)
	)
	(footprint "Vault:TP001V_SMT_100DIA"
		(layer "F.Cu")
		(at 159.2381 115.6691 90)
		(property "Reference" "TP8"
			(at 1.039 0.25687 90)
			(unlocked yes)
			(layer "F.SilkS")
			(effects
				(font
					(size 0.8 0.8)
					(thickness 0.15)
				)
			)
		)
		(property "Value" "SMT_100DIA"
			(at -2.124202 7.0716 0)
			(unlocked yes)
			(layer "F.SilkS")
			(hide yes)
			(effects
				(font
					(size 1.524 1.524)
					(thickness 0.254)
				)
			)
		)
		(sheetname "ZED-F9T")
		(sheetfile "ZED-F9T.kicad_sch")
		(duplicate_pad_numbers_are_jumpers no)
		(pad "1" smd circle
			(at -1.397 0 90)
			(size 1 1)
			(layers "F.Cu" "F.Mask" "F.Paste")
			(net "NetTP8_1")
			(solder_mask_margin 0.05)
			(solder_paste_margin 0)
			(thermal_bridge_angle 90)
		)
	)
)
